# TIMECARD (Time Appliance Project (Time Card)) — schematic netlist excerpt (pin names and nets, part order shuffled) for the footprints in the layout excerpt that follows; sources: Cadence DE-HDL packaged netlist, KiCad conversion of R4006-B0001-02_R01.brd

C69  CAPACITOR  0.1UF 25V 10%  pkg SMC_0402R_H022  page 21 : \1\ = USB_PWR_EN ; \2\ = SG
R99  RESISTOR  4.7KOHM 1%  pkg SMC_0402R_H016  page 21 : \1\ = FPGA_OUT_MACUSBPOWER_EN ; \2\ = SG

(kicad_pcb
	(version 20260206)
	(generator "pcbnew")
	(generator_version "10.0")
	(general
		(thickness 1.6)
		(legacy_teardrops no)
	)
	(paper "A4")
	(title_block
		(title "timecard-production-celestica-r4006 — R4006-B0001-02_R01.brd")
		(comment 1 "Time Appliance Project (Time Card) / footprints 748-749 of 1113")
	)
	(layers
		(0 "F.Cu" signal "TOP")
		(4 "In1.Cu" signal "L02_GND1")
		(6 "In2.Cu" signal "L03_SIG1")
		(8 "In3.Cu" signal "L04_GND2")
		(10 "In4.Cu" signal "L05_VCC1")
		(12 "In5.Cu" signal "L06_VCC2")
		(14 "In6.Cu" signal "L07_GND3")
		(16 "In7.Cu" signal "L08_SIG2")
		(18 "In8.Cu" signal "L09_GND4")
		(2 "B.Cu" signal "BOTTOM")
		(9 "F.Adhes" user "F.Adhesive")
		(11 "B.Adhes" user "B.Adhesive")
		(13 "F.Paste" user "Package Geometry/Pastemask Top")
		(15 "B.Paste" user "Package Geometry/Pastemask Bottom")
		(5 "F.SilkS" user "Ref Des/Silkscreen Top")
		(7 "B.SilkS" user "Ref Des/Silkscreen Bottom")
		(1 "F.Mask" user "Board Geometry/Soldermask Top")
		(3 "B.Mask" user "Board Geometry/Soldermask Bottom")
		(17 "Dwgs.User" user "User.Drawings")
		(19 "Cmts.User" user "User.Comments")
		(21 "Eco1.User" user "User.Eco1")
		(23 "Eco2.User" user "User.Eco2")
		(25 "Edge.Cuts" user "Board Geometry/Outline")
		(27 "Margin" user)
		(31 "F.CrtYd" user "Package Geometry/Place Bound Top")
		(29 "B.CrtYd" user "Package Geometry/Place Bound Bottom")
		(35 "F.Fab" user "Ref Des/Assembly Top")
		(33 "B.Fab" user "Ref Des/Assembly Bottom")
	)
	(footprint ""
		(layer "B.Cu")
		(at 64.516 -55.753 90)
		(property "Reference" "R99"
			(at -6.35 0.34163 270)
			(unlocked yes)
			(layer "B.SilkS")
			(effects
				(font
					(size 0.7874 0.5842)
					(thickness 0.1524)
				)
				(justify mirror)
			)
		)
		(property "Value" "VAL*"
			(at -0.02032 2.13233 90)
			(unlocked yes)
			(layer "B.Fab")
			(hide yes)
			(effects
				(font
					(size 0.7874 0.5842)
					(thickness 0.1524)
				)
				(justify mirror)
			)
		)
		(property "Tolerance" "TOL*"
			(at -0.044704 3.05435 90)
			(unlocked yes)
			(layer "Cmts.User")
			(hide yes)
			(effects
				(font
					(size 0.7874 0.5842)
					(thickness 0.1524)
				)
				(justify mirror)
			)
		)
		(property "User Part Number" "PARTNUM*"
			(at -0.02032 4.024884 90)
			(unlocked yes)
			(layer "Cmts.User")
			(hide yes)
			(effects
				(font
					(size 0.7874 0.5842)
					(thickness 0.1524)
				)
				(justify mirror)
			)
		)
		(property "Device Type" "RESISTOR-G155-14701-01,4.7KOHMA"
			(at -0.008382 1.210564 90)
			(unlocked yes)
			(layer "B.Fab")
			(hide yes)
			(effects
				(font
					(size 0.7874 0.5842)
					(thickness 0.1524)
				)
				(justify mirror)
			)
		)
		(duplicate_pad_numbers_are_jumpers no)
		(fp_line
			(start 1.143 -0.5588)
			(end 1.143 0.5588)
			(stroke
				(width 0.1)
				(type default)
			)
			(layer "B.SilkS")
		)
		(fp_line
			(start -1.143 -0.5588)
			(end 1.143 -0.5588)
			(stroke
				(width 0.1)
				(type default)
			)
			(layer "B.SilkS")
		)
		(fp_line
			(start 1.143 0.5588)
			(end -1.143 0.5588)
			(stroke
				(width 0.1)
				(type default)
			)
			(layer "B.SilkS")
		)
		(fp_line
			(start -1.143 0.5588)
			(end -1.143 -0.5588)
			(stroke
				(width 0.1)
				(type default)
			)
			(layer "B.SilkS")
		)
		(fp_rect
			(start -1.143 -0.5588)
			(end 1.143 0.5588)
			(stroke
				(width 0)
				(type default)
			)
			(fill no)
			(layer "B.CrtYd")
		)
		(fp_line
			(start 0.508 -0.3048)
			(end 0.508 0.3048)
			(stroke
				(width 0.1)
				(type default)
			)
			(layer "B.Fab")
		)
		(fp_line
			(start -0.508 -0.3048)
			(end 0.508 -0.3048)
			(stroke
				(width 0.1)
				(type default)
			)
			(layer "B.Fab")
		)
		(fp_line
			(start 0.508 0.3048)
			(end -0.508 0.3048)
			(stroke
				(width 0.1)
				(type default)
			)
			(layer "B.Fab")
		)
		(fp_line
			(start -0.508 0.3048)
			(end -0.508 -0.3048)
			(stroke
				(width 0.1)
				(type default)
			)
			(layer "B.Fab")
		)
		(pad "1" smd rect
			(at 0.5334 0 270)
			(size 0.7112 0.6096)
			(layers "B.Cu" "B.Mask" "B.Paste")
			(net "FPGA_OUT_MACUSBPOWER_EN")
		)
		(pad "2" smd rect
			(at -0.5334 0 270)
			(size 0.7112 0.6096)
			(layers "B.Cu" "B.Mask" "B.Paste")
			(net "SG")
		)
		(zone
			(layer "B.Cu")
			(hatch none 0.5)
			(connect_pads
				(clearance 0)
			)
			(min_thickness 0.25)
			(keepout
				(tracks allowed)
				(vias not_allowed)
				(pads allowed)
				(copperpour not_allowed)
				(footprints allowed)
			)
			(placement
				(enabled no)
				(sheetname "")
			)
			(fill
				(thermal_gap 0.5)
				(thermal_bridge_width 0.5)
				(island_removal_mode 0)
			)
			(polygon
				(pts
					(xy 64.2112 -55.6768) (xy 64.8208 -55.6768) (xy 64.8208 -55.8292) (xy 64.2112 -55.8292)
				)
			)
		)
	)
	(footprint ""
		(layer "B.Cu")
		(at 65.786 -58.039 90)
		(property "Reference" "C69"
			(at -2.794 -0.03937 270)
			(unlocked yes)
			(layer "B.SilkS")
			(effects
				(font
					(size 0.7874 0.5842)
					(thickness 0.1524)
				)
				(justify mirror)
			)
		)
		(property "Value" "VAL*"
			(at -0.0762 2.067306 90)
			(unlocked yes)
			(layer "B.Fab")
			(hide yes)
			(effects
				(font
					(size 0.7874 0.5842)
					(thickness 0.1524)
				)
				(justify mirror)
			)
		)
		(property "Device Type" "CAPACITOR-G105-0B104-EK,0.1UF,A"
			(at -0.0508 1.127506 90)
			(unlocked yes)
			(layer "B.Fab")
			(hide yes)
			(effects
				(font
					(size 0.7874 0.5842)
					(thickness 0.1524)
				)
				(justify mirror)
			)
		)
		(property "User Part Number" "PARTNUM*"
			(at -0.1016 4.023106 90)
			(unlocked yes)
			(layer "Cmts.User")
			(hide yes)
			(effects
				(font
					(size 0.7874 0.5842)
					(thickness 0.1524)
				)
				(justify mirror)
			)
		)
		(property "Tolerance" "TOL*"
			(at -0.0762 3.032506 90)
			(unlocked yes)
			(layer "Cmts.User")
			(hide yes)
			(effects
				(font
					(size 0.7874 0.5842)
					(thickness 0.1524)
				)
				(justify mirror)
			)
		)
		(duplicate_pad_numbers_are_jumpers no)
		(fp_line
			(start 1.143 -0.5588)
			(end 1.143 0.5588)
			(stroke
				(width 0.1)
				(type default)
			)
			(layer "B.SilkS")
		)
		(fp_line
			(start -1.143 -0.5588)
			(end 1.143 -0.5588)
			(stroke
				(width 0.1)
				(type default)
			)
			(layer "B.SilkS")
		)
		(fp_line
			(start 1.143 0.5588)
			(end -1.143 0.5588)
			(stroke
				(width 0.1)
				(type default)
			)
			(layer "B.SilkS")
		)
		(fp_line
			(start -1.143 0.5588)
			(end -1.143 -0.5588)
			(stroke
				(width 0.1)
				(type default)
			)
			(layer "B.SilkS")
		)
		(fp_rect
			(start -1.143 -0.5588)
			(end 1.143 0.5588)
			(stroke
				(width 0)
				(type default)
			)
			(fill no)
			(layer "B.CrtYd")
		)
		(fp_line
			(start 0.508 -0.3048)
			(end 0.508 0.3048)
			(stroke
				(width 0.1)
				(type default)
			)
			(layer "B.Fab")
		)
		(fp_line
			(start -0.508 -0.3048)
			(end 0.508 -0.3048)
			(stroke
				(width 0.1)
				(type default)
			)
			(layer "B.Fab")
		)
		(fp_line
			(start 0.508 0.3048)
			(end -0.508 0.3048)
			(stroke
				(width 0.1)
				(type default)
			)
			(layer "B.Fab")
		)
		(fp_line
			(start -0.508 0.3048)
			(end -0.508 -0.3048)
			(stroke
				(width 0.1)
				(type default)
			)
			(layer "B.Fab")
		)
		(pad "1" smd rect
			(at 0.5334 0 270)
			(size 0.7112 0.6096)
			(layers "B.Cu" "B.Mask" "B.Paste")
			(net "USB_PWR_EN")
		)
		(pad "2" smd rect
			(at -0.5334 0 270)
			(size 0.7112 0.6096)
			(layers "B.Cu" "B.Mask" "B.Paste")
			(net "SG")
		)
		(zone
			(layer "B.Cu")
			(hatch none 0.5)
			(connect_pads
				(clearance 0)
			)
			(min_thickness 0.25)
			(keepout
				(tracks allowed)
				(vias not_allowed)
				(pads allowed)
				(copperpour not_allowed)
				(footprints allowed)
			)
			(placement
				(enabled no)
				(sheetname "")
			)
			(fill
				(thermal_gap 0.5)
				(thermal_bridge_width 0.5)
				(island_removal_mode 0)
			)
			(polygon
				(pts
					(xy 65.4812 -57.9628) (xy 66.0908 -57.9628) (xy 66.0908 -58.1152) (xy 65.4812 -58.1152)
				)
			)
		)
	)
)
